(kicad_pcb
	(version 20241229)
	(generator "pcbnew")
	(generator_version "9.0")
	(general
		(thickness 1.6642)
		(legacy_teardrops no)
	)
	(paper "A3")
	(title_block
		(title "PolarFire SoM")
		(date "2025-07-22")
		(rev "1.1.4")
		(company "Antmicro Ltd")
		(comment 1 "www.antmicro.com")
		(comment 9 "footprint 127 of 470 (J4), pads 95-104 of 104")
	)
	(layers
		(0 "F.Cu" mixed)
		(4 "In1.Cu" power)
		(6 "In2.Cu" signal)
		(8 "In3.Cu" power)
		(10 "In4.Cu" signal)
		(12 "In5.Cu" power)
		(14 "In6.Cu" power)
		(16 "In7.Cu" signal)
		(18 "In8.Cu" power)
		(20 "In9.Cu" signal)
		(22 "In10.Cu" power)
		(24 "In11.Cu" signal)
		(26 "In12.Cu" signal)
		(2 "B.Cu" mixed)
		(9 "F.Adhes" user "F.Adhesive")
		(11 "B.Adhes" user "B.Adhesive")
		(13 "F.Paste" user)
		(15 "B.Paste" user)
		(5 "F.SilkS" user "F.Silkscreen")
		(7 "B.SilkS" user "B.Silkscreen")
		(1 "F.Mask" user)
		(3 "B.Mask" user)
		(17 "Dwgs.User" user "User.Drawings")
		(19 "Cmts.User" user "User.Comments")
		(21 "Eco1.User" user "User.Eco1")
		(23 "Eco2.User" user "User.Eco2")
		(25 "Edge.Cuts" user)
		(27 "Margin" user)
		(31 "F.CrtYd" user "F.Courtyard")
		(29 "B.CrtYd" user "B.Courtyard")
		(35 "F.Fab" user)
		(33 "B.Fab" user)
	)
	(footprint "antmicro-footprints:Conn_Plug_Hirose_DF40_2x50_DF40C-100DP-0.4V"
		(layer "B.Cu")
		(at 199.52 152.838 180)
		(property "Reference" "J4"
			(at -10.91 1.838 0)
			(layer "B.SilkS")
			(effects
				(font
					(size 0.7 0.7)
					(thickness 0.15)
				)
				(justify left bottom mirror)
			)
		)
		(property "Value" "Plug_Hirose_DF40_2x50_DF40C-100DP-0.4V"
			(at 0.001 -2.8 0)
			(layer "B.Fab")
			(hide yes)
			(effects
				(font
					(size 0.7 0.7)
					(thickness 0.15)
				)
				(justify left bottom mirror)
			)
		)
		(property "Datasheet" "https://www.hirose.com/en/product/document?clcode=CL0684-4032-1-51&productname=DF40C-100DP-0.4V(51)&series=DF40&documenttype=2DDrawing&lang=en&documentid=0001001212"
			(at 0 0 180)
			(layer "F.Fab")
			(hide yes)
			(effects
				(font
					(size 1.27 1.27)
					(thickness 0.15)
				)
			)
		)
		(property "Description" "Mezzanine Connector, Header, 0.4 mm, 2 Rows, 100 Contacts, Surface Mount, Phosphor Bronze"
			(at 0 0 180)
			(layer "F.Fab")
			(hide yes)
			(effects
				(font
					(size 1.27 1.27)
					(thickness 0.15)
				)
			)
		)
		(property "Author" "Antmicro"
			(at 399.04 305.676 0)
			(layer "B.Fab")
			(hide yes)
			(effects
				(font
					(size 1 1)
					(thickness 0.15)
				)
				(justify mirror)
			)
		)
		(property "License" "Apache-2.0"
			(at 399.04 305.676 0)
			(layer "B.Fab")
			(hide yes)
			(effects
				(font
					(size 1 1)
					(thickness 0.15)
				)
				(justify mirror)
			)
		)
		(property "MPN" "DF40C-100DP-0.4V(51)"
			(at 399.04 305.676 0)
			(layer "B.Fab")
			(hide yes)
			(effects
				(font
					(size 1 1)
					(thickness 0.15)
				)
				(justify mirror)
			)
		)
		(property "Manufacturer" "Hirose Electric"
			(at 399.04 305.676 0)
			(layer "B.Fab")
			(hide yes)
			(effects
				(font
					(size 1 1)
					(thickness 0.15)
				)
				(justify mirror)
			)
		)
		(property "Pitch" "0.4 mm"
			(at 399.04 305.676 0)
			(layer "B.Fab")
			(hide yes)
			(effects
				(font
					(size 1 1)
					(thickness 0.15)
				)
				(justify mirror)
			)
		)
		(sheetname "/Bottom Connector/")
		(sheetfile "bottom-connector.kicad_sch")
		(attr smd)
		(pad "95" smd rect
			(at 9 1.377 180)
			(size 0.23 0.66)
			(layers "B.Cu" "B.Mask" "B.Paste")
			(net 199 "/Bottom Connector/DSI1.D2_P")
			(pintype "passive")
		)
		(pad "96" smd rect
			(at 9 -1.333 180)
			(size 0.23 0.66)
			(layers "B.Cu" "B.Mask" "B.Paste")
			(net 201 "/Bottom Connector/DSI1.D3_P")
			(pintype "passive")
		)
		(pad "97" smd rect
			(at 9.401 1.377 180)
			(size 0.23 0.66)
			(layers "B.Cu" "B.Mask" "B.Paste")
			(net 417 "GND")
			(pintype "passive")
		)
		(pad "98" smd rect
			(at 9.401 -1.333 180)
			(size 0.23 0.66)
			(layers "B.Cu" "B.Mask" "B.Paste")
			(net 417 "GND")
			(pintype "passive")
		)
		(pad "99" smd rect
			(at 9.803 1.377 180)
			(size 0.23 0.66)
			(layers "B.Cu" "B.Mask" "B.Paste")
			(net 206 "/Bottom Connector/HDMI0.SDA")
			(pintype "passive")
		)
		(pad "100" smd rect
			(at 9.803 -1.333 180)
			(size 0.23 0.66)
			(layers "B.Cu" "B.Mask" "B.Paste")
			(net 218 "/Bottom Connector/HDMI0.SCL")
			(pintype "passive")
		)
		(pad "MP" smd rect
			(at -10.274 -1.333 180)
			(size 0.35 0.66)
			(layers "B.Cu" "B.Mask" "B.Paste")
			(net 417 "GND")
			(pinfunction "MP")
			(pintype "passive")
		)
		(pad "MP" smd rect
			(at -10.274 1.377 180)
			(size 0.35 0.66)
			(layers "B.Cu" "B.Mask" "B.Paste")
			(net 417 "GND")
			(pinfunction "MP")
			(pintype "passive")
		)
		(pad "MP" smd rect
			(at 10.276 -1.333 180)
			(size 0.35 0.66)
			(layers "B.Cu" "B.Mask" "B.Paste")
			(net 417 "GND")
			(pinfunction "MP")
			(pintype "passive")
		)
		(pad "MP" smd rect
			(at 10.276 1.377 180)
			(size 0.35 0.66)
			(layers "B.Cu" "B.Mask" "B.Paste")
			(net 417 "GND")
			(pinfunction "MP")
			(pintype "passive")
		)
	)
)
